FILE_TYPE = CONNECTIVITY;
{Allegro Design Entry HDL 17.2-2016 S081 (4005846) 1/11/2022}
"PAGE_NUMBER" = 67;
0"NC";
1"PVCCIN_CPU1\g";
2"PVCCIN_CPU1\g";
3"PVCCIN_CPU1\g";
4"PVCCIN_CPU1\g";
%"SOCKET4677_AZIF0045P001C01CS"
"26","(-650,1900)","0","pure_quanta","I1";
;
PART_NUMBER"DGA^7000023"
VALUE"SOCKET4677_AZIF0045-P001C01CS"
MATERIAL"IO"
PART_TYPE"SMLF"
$LOCATION"U1"
CDS_LMAN_SYM_OUTLINE"-1050,2000,1050,-2000"
NEEDS_NO_SIZE"TRUE"
CDS_LIB"pure_quanta"
CDS_LOCATION"U1"
$SEC"26"
CDS_SEC"26";
"VCCIN190"
$PN"BW80"3;
"VCCIN191"
$PN"BW82"3;
"VCCIN192"
$PN"BW84"3;
"VCCIN193"
$PN"BW86"3;
"VCCIN194"
$PN"BW88"3;
"VCCIN195"
$PN"BW90"3;
"VCCIN196"
$PN"BY32"3;
"VCCIN197"
$PN"BY34"3;
"VCCIN198"
$PN"BY36"3;
"VCCIN199"
$PN"BY38"3;
"VCCIN200"
$PN"BY40"3;
"VCCIN201"
$PN"BY42"3;
"VCCIN202"
$PN"BY44"3;
"VCCIN203"
$PN"BY47"3;
"VCCIN204"
$PN"BY49"3;
"VCCIN205"
$PN"BY51"3;
"VCCIN206"
$PN"BY53"3;
"VCCIN207"
$PN"BY55"3;
"VCCIN208"
$PN"BY57"3;
"VCCIN209"
$PN"BY59"3;
"VCCIN210"
$PN"BY61"3;
"VCCIN211"
$PN"BY63"3;
"VCCIN212"
$PN"BY65"3;
"VCCIN213"
$PN"BY67"3;
"VCCIN214"
$PN"BY69"3;
"VCCIN215"
$PN"BY71"3;
"VCCIN216"
$PN"BY73"3;
"VCCIN217"
$PN"BY75"3;
"VCCIN218"
$PN"BY77"3;
"VCCIN219"
$PN"BY79"3;
"VCCIN220"
$PN"BY81"3;
"VCCIN221"
$PN"BY83"3;
"VCCIN222"
$PN"BY85"3;
"VCCIN223"
$PN"BY87"3;
"VCCIN224"
$PN"BY89"3;
"VCCIN225"
$PN"CA33"3;
"VCCIN226"
$PN"CA35"3;
"VCCIN227"
$PN"CA37"3;
"VCCIN228"
$PN"CA39"3;
"VCCIN229"
$PN"CA41"3;
"VCCIN230"
$PN"CA43"3;
"VCCIN231"
$PN"CA45"3;
"VCCIN232"
$PN"CA48"3;
"VCCIN233"
$PN"CA50"3;
"VCCIN234"
$PN"CA52"3;
"VCCIN235"
$PN"CA54"3;
"VCCIN236"
$PN"CA56"3;
"VCCIN237"
$PN"CA58"3;
"VCCIN238"
$PN"CA60"3;
"VCCIN239"
$PN"CA62"3;
"VCCIN240"
$PN"CA64"3;
"VCCIN241"
$PN"CA66"3;
"VCCIN242"
$PN"CA68"3;
"VCCIN243"
$PN"CA70"3;
"VCCIN244"
$PN"CA72"3;
"VCCIN245"
$PN"CA74"3;
"VCCIN246"
$PN"CA76"3;
"VCCIN247"
$PN"CA78"3;
"VCCIN248"
$PN"CA80"3;
"VCCIN249"
$PN"CA82"3;
"VCCIN250"
$PN"CA84"3;
"VCCIN251"
$PN"CA86"3;
"VCCIN252"
$PN"CA88"3;
"VCCIN253"
$PN"CA90"3;
"VCCIN254"
$PN"CB61"3;
"VCCIN255"
$PN"CB75"3;
"VCCIN256"
$PN"CB77"3;
"VCCIN257"
$PN"CC33"3;
"VCCIN258"
$PN"CC35"3;
"VCCIN259"
$PN"CC37"3;
"VCCIN260"
$PN"CC39"3;
"VCCIN261"
$PN"CC41"3;
"VCCIN262"
$PN"CC43"3;
"VCCIN263"
$PN"CC45"3;
"VCCIN264"
$PN"CC48"3;
"VCCIN265"
$PN"CC50"4;
"VCCIN266"
$PN"CC52"4;
"VCCIN267"
$PN"CC54"4;
"VCCIN268"
$PN"CC56"4;
"VCCIN269"
$PN"CC58"4;
"VCCIN270"
$PN"CC60"4;
"VCCIN271"
$PN"CC76"4;
"VCCIN272"
$PN"CC78"4;
"VCCIN273"
$PN"CC80"4;
"VCCIN274"
$PN"CC82"4;
"VCCIN275"
$PN"CC84"4;
"VCCIN276"
$PN"CC86"4;
"VCCIN277"
$PN"CC88"4;
"VCCIN278"
$PN"CC90"4;
"VCCIN279"
$PN"CD32"4;
"VCCIN280"
$PN"CD34"4;
"VCCIN281"
$PN"CD36"4;
"VCCIN282"
$PN"CD38"4;
"VCCIN283"
$PN"CD40"4;
"VCCIN284"
$PN"CD42"4;
"VCCIN285"
$PN"CD44"4;
"VCCIN286"
$PN"CD47"4;
"VCCIN287"
$PN"CD49"4;
"VCCIN288"
$PN"CD51"4;
"VCCIN289"
$PN"CD53"4;
"VCCIN290"
$PN"CD55"4;
"VCCIN291"
$PN"CD57"4;
"VCCIN292"
$PN"CD59"4;
"VCCIN293"
$PN"CD79"4;
"VCCIN294"
$PN"CD81"4;
"VCCIN295"
$PN"CD83"4;
"VCCIN296"
$PN"CD85"4;
"VCCIN297"
$PN"CD87"4;
"VCCIN298"
$PN"CD89"4;
"VCCIN299"
$PN"CE80"4;
"VCCIN300"
$PN"CE82"4;
"VCCIN301"
$PN"CE84"4;
"VCCIN302"
$PN"CE86"4;
"VCCIN303"
$PN"CE88"4;
"VCCIN304"
$PN"CE90"4;
"VCCIN305"
$PN"CF79"4;
"VCCIN306"
$PN"CF81"4;
"VCCIN307"
$PN"CF83"4;
"VCCIN308"
$PN"CF85"4;
"VCCIN309"
$PN"CF87"4;
"VCCIN310"
$PN"CF89"4;
"VCCIN311"
$PN"CF91"4;
"VCCIN312"
$PN"CG80"4;
"VCCIN313"
$PN"CG82"4;
"VCCIN314"
$PN"CG84"4;
"VCCIN315"
$PN"CG86"4;
"VCCIN316"
$PN"CG88"4;
"VCCIN317"
$PN"CG90"4;
"VCCIN318"
$PN"CH81"4;
"VCCIN319"
$PN"CH91"4;
"VCCIN320"
$PN"CJ82"4;
"VCCIN321"
$PN"CJ84"4;
"VCCIN322"
$PN"CJ86"4;
"VCCIN323"
$PN"CJ88"4;
"VCCIN324"
$PN"CJ90"4;
"VCCIN325"
$PN"CK83"4;
"VCCIN326"
$PN"CK85"4;
"VCCIN327"
$PN"CK87"4;
"VCCIN328"
$PN"CK89"4;
"VCCIN329"
$PN"CK91"4;
"VCCIN330"
$PN"CL84"4;
"VCCIN331"
$PN"CL86"4;
"VCCIN332"
$PN"CL88"4;
"VCCIN333"
$PN"CL90"4;
"VCCIN334"
$PN"CM87"4;
"VCCIN335"
$PN"CM91"4;
"VCCIN336"
$PN"CN88"4;
"VCCIN337"
$PN"CN90"4;
"VCCIN338"
$PN"CP89"4;
"VCCIN339"
$PN"CM89"4;
%"VCC_CORE"
"1","(-2100,3975)","0","logical_power","I2";
;
HDL_POWER"PVCCIN_CPU1"
CDS_LIB"logical_power";
"A"4;
%"SOCKET4677_AZIF0045P001C01CS"
"27","(3725,1900)","0","pure_quanta","I3";
;
PART_NUMBER"DGA^7000023"
VALUE"SOCKET4677_AZIF0045-P001C01CS"
MATERIAL"IO"
PART_TYPE"SMLF"
$LOCATION"U1"
CDS_LMAN_SYM_OUTLINE"-1050,2000,1050,-2000"
NEEDS_NO_SIZE"TRUE"
CDS_LIB"pure_quanta"
CDS_LOCATION"U1"
$SEC"27"
CDS_SEC"27";
"VCCIN40"
$PN"BN43"2;
"VCCIN41"
$PN"BN45"2;
"VCCIN42"
$PN"BN48"2;
"VCCIN43"
$PN"BN50"2;
"VCCIN44"
$PN"BN52"2;
"VCCIN45"
$PN"BN54"2;
"VCCIN46"
$PN"BN56"2;
"VCCIN47"
$PN"BN58"2;
"VCCIN48"
$PN"BN60"2;
"VCCIN49"
$PN"BN78"2;
"VCCIN50"
$PN"BN80"2;
"VCCIN51"
$PN"BN82"2;
"VCCIN52"
$PN"BN84"2;
"VCCIN53"
$PN"BN86"2;
"VCCIN54"
$PN"BN88"2;
"VCCIN55"
$PN"BN90"2;
"VCCIN56"
$PN"BP32"2;
"VCCIN57"
$PN"BP34"2;
"VCCIN58"
$PN"BP36"2;
"VCCIN59"
$PN"BP38"2;
"VCCIN60"
$PN"BP40"2;
"VCCIN61"
$PN"BP42"2;
"VCCIN62"
$PN"BP44"2;
"VCCIN63"
$PN"BP47"2;
"VCCIN64"
$PN"BP49"2;
"VCCIN65"
$PN"BP51"2;
"VCCIN66"
$PN"BP53"2;
"VCCIN67"
$PN"BP55"2;
"VCCIN68"
$PN"BP57"2;
"VCCIN69"
$PN"BP59"2;
"VCCIN70"
$PN"BP61"2;
"VCCIN71"
$PN"BP79"2;
"VCCIN72"
$PN"BP81"2;
"VCCIN73"
$PN"BP83"2;
"VCCIN74"
$PN"BP85"2;
"VCCIN75"
$PN"BP87"2;
"VCCIN76"
$PN"BP89"2;
"VCCIN77"
$PN"BR60"2;
"VCCIN78"
$PN"BR62"2;
"VCCIN79"
$PN"BR78"2;
"VCCIN80"
$PN"BT32"2;
"VCCIN81"
$PN"BT34"2;
"VCCIN82"
$PN"BT36"2;
"VCCIN83"
$PN"BT38"2;
"VCCIN84"
$PN"BT40"2;
"VCCIN85"
$PN"BT42"2;
"VCCIN86"
$PN"BT44"2;
"VCCIN87"
$PN"BT47"2;
"VCCIN88"
$PN"BT49"2;
"VCCIN89"
$PN"BT51"2;
"VCCIN90"
$PN"BT53"2;
"VCCIN91"
$PN"BT55"2;
"VCCIN92"
$PN"BT57"2;
"VCCIN93"
$PN"BT59"2;
"VCCIN94"
$PN"BT61"2;
"VCCIN95"
$PN"BT63"2;
"VCCIN96"
$PN"BT65"2;
"VCCIN97"
$PN"BT67"2;
"VCCIN98"
$PN"BT69"2;
"VCCIN99"
$PN"BT71"2;
"VCCIN100"
$PN"BT73"2;
"VCCIN101"
$PN"BT75"2;
"VCCIN102"
$PN"BT77"2;
"VCCIN103"
$PN"BT79"2;
"VCCIN104"
$PN"BT81"2;
"VCCIN105"
$PN"BT83"2;
"VCCIN106"
$PN"BT85"2;
"VCCIN107"
$PN"BT87"2;
"VCCIN108"
$PN"BT89"2;
"VCCIN109"
$PN"BU33"2;
"VCCIN110"
$PN"BU35"2;
"VCCIN111"
$PN"BU37"2;
"VCCIN112"
$PN"BU39"2;
"VCCIN113"
$PN"BU41"2;
"VCCIN114"
$PN"BU43"2;
"VCCIN115"
$PN"BU45"1;
"VCCIN116"
$PN"BU48"1;
"VCCIN117"
$PN"BU50"1;
"VCCIN118"
$PN"BU52"1;
"VCCIN119"
$PN"BU54"1;
"VCCIN120"
$PN"BU56"1;
"VCCIN121"
$PN"BU58"1;
"VCCIN122"
$PN"BU60"1;
"VCCIN123"
$PN"BU62"1;
"VCCIN124"
$PN"BU64"1;
"VCCIN125"
$PN"BU66"1;
"VCCIN126"
$PN"BU68"1;
"VCCIN127"
$PN"BU70"1;
"VCCIN128"
$PN"BU72"1;
"VCCIN129"
$PN"BU74"1;
"VCCIN130"
$PN"BU76"1;
"VCCIN131"
$PN"BU78"1;
"VCCIN132"
$PN"BU80"1;
"VCCIN133"
$PN"BU82"1;
"VCCIN134"
$PN"BU84"1;
"VCCIN135"
$PN"BU86"1;
"VCCIN136"
$PN"BU88"1;
"VCCIN137"
$PN"BU90"1;
"VCCIN138"
$PN"BV32"1;
"VCCIN139"
$PN"BV34"1;
"VCCIN140"
$PN"BV36"1;
"VCCIN141"
$PN"BV38"1;
"VCCIN142"
$PN"BV40"1;
"VCCIN143"
$PN"BV42"1;
"VCCIN144"
$PN"BV44"1;
"VCCIN145"
$PN"BV47"1;
"VCCIN146"
$PN"BV49"1;
"VCCIN147"
$PN"BV51"1;
"VCCIN148"
$PN"BV53"1;
"VCCIN149"
$PN"BV55"1;
"VCCIN150"
$PN"BV57"1;
"VCCIN151"
$PN"BV59"1;
"VCCIN152"
$PN"BV61"1;
"VCCIN153"
$PN"BV63"1;
"VCCIN154"
$PN"BV65"1;
"VCCIN155"
$PN"BV67"1;
"VCCIN156"
$PN"BV69"1;
"VCCIN157"
$PN"BV71"1;
"VCCIN158"
$PN"BV73"1;
"VCCIN159"
$PN"BV75"1;
"VCCIN160"
$PN"BV77"1;
"VCCIN161"
$PN"BV79"1;
"VCCIN162"
$PN"BV81"1;
"VCCIN163"
$PN"BV83"1;
"VCCIN164"
$PN"BV85"1;
"VCCIN165"
$PN"BV87"1;
"VCCIN166"
$PN"BV89"1;
"VCCIN167"
$PN"BW33"1;
"VCCIN168"
$PN"BW35"1;
"VCCIN169"
$PN"BW37"1;
"VCCIN170"
$PN"BW39"1;
"VCCIN171"
$PN"BW41"1;
"VCCIN172"
$PN"BW43"1;
"VCCIN173"
$PN"BW45"1;
"VCCIN174"
$PN"BW48"1;
"VCCIN175"
$PN"BW50"1;
"VCCIN176"
$PN"BW52"1;
"VCCIN177"
$PN"BW54"1;
"VCCIN178"
$PN"BW56"1;
"VCCIN179"
$PN"BW58"1;
"VCCIN180"
$PN"BW60"1;
"VCCIN181"
$PN"BW62"1;
"VCCIN182"
$PN"BW64"1;
"VCCIN183"
$PN"BW66"1;
"VCCIN184"
$PN"BW68"1;
"VCCIN185"
$PN"BW70"1;
"VCCIN186"
$PN"BW72"1;
"VCCIN187"
$PN"BW74"1;
"VCCIN188"
$PN"BW76"1;
"VCCIN189"
$PN"BW78"1;
%"VCC_CORE"
"1","(800,3975)","0","logical_power","I4";
;
HDL_POWER"PVCCIN_CPU1"
CDS_LIB"logical_power";
"A"3;
%"VCC_CORE"
"1","(2275,3975)","0","logical_power","I5";
;
HDL_POWER"PVCCIN_CPU1"
CDS_LIB"logical_power";
"A"1;
%"VCC_CORE"
"1","(5175,3975)","0","logical_power","I6";
;
HDL_POWER"PVCCIN_CPU1"
CDS_LIB"logical_power";
"A"2;
END.
